# TIMECARD (Time Appliance Project (Time Card)) — schematic netlist excerpt (pin names and nets, part order shuffled) for the footprints in the layout excerpt that follows; sources: Cadence DE-HDL packaged netlist, KiCad conversion of R4006-B0001-02_R01.brd

TP139  TP_PIONT  pkg TP010CT020B030_PTH  page 25 : \1\ = IO_L23N_34
SP62  NULL  pkg DUMMY  page 34
R310  RESISTOR  0OHM -  pkg SMC_0402R_H016  page 16 : \1\ = RGB_LED_I2C_SDA ; \2\ = R_PCA9546_I2C_SDA

(kicad_pcb
	(version 20260206)
	(generator "pcbnew")
	(generator_version "10.0")
	(general
		(thickness 1.6)
		(legacy_teardrops no)
	)
	(paper "A4")
	(title_block
		(title "timecard-production-celestica-r4006 — R4006-B0001-02_R01.brd")
		(comment 1 "Time Appliance Project (Time Card) / footprints 571-573 of 1113")
	)
	(layers
		(0 "F.Cu" signal "TOP")
		(4 "In1.Cu" signal "L02_GND1")
		(6 "In2.Cu" signal "L03_SIG1")
		(8 "In3.Cu" signal "L04_GND2")
		(10 "In4.Cu" signal "L05_VCC1")
		(12 "In5.Cu" signal "L06_VCC2")
		(14 "In6.Cu" signal "L07_GND3")
		(16 "In7.Cu" signal "L08_SIG2")
		(18 "In8.Cu" signal "L09_GND4")
		(2 "B.Cu" signal "BOTTOM")
		(9 "F.Adhes" user "F.Adhesive")
		(11 "B.Adhes" user "B.Adhesive")
		(13 "F.Paste" user "Package Geometry/Pastemask Top")
		(15 "B.Paste" user "Package Geometry/Pastemask Bottom")
		(5 "F.SilkS" user "Ref Des/Silkscreen Top")
		(7 "B.SilkS" user "Ref Des/Silkscreen Bottom")
		(1 "F.Mask" user "Board Geometry/Soldermask Top")
		(3 "B.Mask" user "Board Geometry/Soldermask Bottom")
		(17 "Dwgs.User" user "User.Drawings")
		(19 "Cmts.User" user "User.Comments")
		(21 "Eco1.User" user "User.Eco1")
		(23 "Eco2.User" user "User.Eco2")
		(25 "Edge.Cuts" user "Board Geometry/Outline")
		(27 "Margin" user)
		(31 "F.CrtYd" user "Package Geometry/Place Bound Top")
		(29 "B.CrtYd" user "Package Geometry/Place Bound Bottom")
		(35 "F.Fab" user "Ref Des/Assembly Top")
		(33 "B.Fab" user "Ref Des/Assembly Bottom")
	)
	(footprint ""
		(layer "F.Cu")
		(at 124.841 -37.719)
		(property "Reference" "TP139"
			(at -2.00025 2.2098 90)
			(unlocked yes)
			(layer "F.SilkS")
			(effects
				(font
					(size 0.635 0.4064)
					(thickness 0.1524)
				)
				(justify left)
			)
		)
		(property "Value" ""
			(at 0 0 0)
			(layer "F.Fab")
			(effects
				(font
					(size 1.27 1.27)
				)
			)
		)
		(property "Device Type" "TP_PIONT-TP010CT020B030_PTH-TPA"
			(at -1.341882 0.996696 0)
			(unlocked yes)
			(layer "F.Fab")
			(hide yes)
			(effects
				(font
					(size 0.7874 0.5842)
					(thickness 0.1524)
				)
				(justify left)
			)
		)
		(duplicate_pad_numbers_are_jumpers no)
		(fp_poly
			(pts
				(arc
					(start 0.889 0)
					(mid -0.889 0)
					(end 0.889 0)
				)
			)
			(stroke
				(width 0)
				(type default)
			)
			(fill no)
			(layer "B.CrtYd")
		)
		(fp_poly
			(pts
				(arc
					(start 0.889 0)
					(mid -0.889 0)
					(end 0.889 0)
				)
			)
			(stroke
				(width 0)
				(type default)
			)
			(fill no)
			(layer "F.CrtYd")
		)
		(pad "1" thru_hole circle
			(at 0 0)
			(size 0.508 0.508)
			(drill 0.254)
			(layers "*.Cu" "*.Mask")
			(remove_unused_layers no)
			(net "IO_L23N_34")
			(clearance 0.1016)
			(padstack
				(mode front_inner_back)
				(layer "Inner"
					(shape circle)
					(size 0.508 0.508)
					(clearance 0.1016)
				)
				(layer "B.Cu"
					(shape circle)
					(size 0.762 0.762)
					(clearance -0.0254)
				)
			)
		)
	)
	(footprint ""
		(layer "F.Cu")
		(at 48.006 -131.445)
		(property "Reference" "SP62"
			(at 0 0 0)
			(layer "F.SilkS")
			(hide yes)
			(effects
				(font
					(size 1.27 1.27)
				)
			)
		)
		(property "Value" ""
			(at 0 0 0)
			(layer "F.Fab")
			(effects
				(font
					(size 1.27 1.27)
				)
			)
		)
		(duplicate_pad_numbers_are_jumpers no)
	)
	(footprint ""
		(layer "F.Cu")
		(at 74.0664 -82.7786)
		(property "Reference" "R310"
			(at -0.1524 -4.17703 0)
			(unlocked yes)
			(layer "F.SilkS")
			(effects
				(font
					(size 0.7874 0.5842)
					(thickness 0.1524)
				)
			)
		)
		(property "Value" "VAL*"
			(at 0.02032 2.13233 0)
			(unlocked yes)
			(layer "F.Fab")
			(hide yes)
			(effects
				(font
					(size 0.7874 0.5842)
					(thickness 0.1524)
				)
			)
		)
		(property "Tolerance" "TOL*"
			(at 0.044704 3.05435 0)
			(unlocked yes)
			(layer "Cmts.User")
			(hide yes)
			(effects
				(font
					(size 0.7874 0.5842)
					(thickness 0.1524)
				)
			)
		)
		(property "User Part Number" "PARTNUM*"
			(at 0.02032 4.024884 0)
			(unlocked yes)
			(layer "Cmts.User")
			(hide yes)
			(effects
				(font
					(size 0.7874 0.5842)
					(thickness 0.1524)
				)
			)
		)
		(property "Device Type" "RESISTOR-G155-100R0-J0,0OHM,-"
			(at 0.008382 1.210564 0)
			(unlocked yes)
			(layer "F.Fab")
			(hide yes)
			(effects
				(font
					(size 0.7874 0.5842)
					(thickness 0.1524)
				)
			)
		)
		(duplicate_pad_numbers_are_jumpers no)
		(fp_line
			(start -1.143 -0.5588)
			(end -1.143 0.5588)
			(stroke
				(width 0.1)
				(type default)
			)
			(layer "F.SilkS")
		)
		(fp_line
			(start -1.143 0.5588)
			(end 1.143 0.5588)
			(stroke
				(width 0.1)
				(type default)
			)
			(layer "F.SilkS")
		)
		(fp_line
			(start 1.143 -0.5588)
			(end -1.143 -0.5588)
			(stroke
				(width 0.1)
				(type default)
			)
			(layer "F.SilkS")
		)
		(fp_line
			(start 1.143 0.5588)
			(end 1.143 -0.5588)
			(stroke
				(width 0.1)
				(type default)
			)
			(layer "F.SilkS")
		)
		(fp_poly
			(pts
				(xy -1.143 0.5588) (xy 1.143 0.5588) (xy 1.143 -0.5588) (xy -1.143 -0.5588)
			)
			(stroke
				(width 0)
				(type default)
			)
			(fill no)
			(layer "F.CrtYd")
		)
		(fp_line
			(start -0.508 -0.3048)
			(end -0.508 0.3048)
			(stroke
				(width 0.1)
				(type default)
			)
			(layer "F.Fab")
		)
		(fp_line
			(start -0.508 0.3048)
			(end 0.508 0.3048)
			(stroke
				(width 0.1)
				(type default)
			)
			(layer "F.Fab")
		)
		(fp_line
			(start 0.508 -0.3048)
			(end -0.508 -0.3048)
			(stroke
				(width 0.1)
				(type default)
			)
			(layer "F.Fab")
		)
		(fp_line
			(start 0.508 0.3048)
			(end 0.508 -0.3048)
			(stroke
				(width 0.1)
				(type default)
			)
			(layer "F.Fab")
		)
		(pad "1" smd rect
			(at -0.5334 0)
			(size 0.7112 0.6096)
			(layers "F.Cu" "F.Mask" "F.Paste")
			(net "RGB_LED_I2C_SDA")
		)
		(pad "2" smd rect
			(at 0.5334 0)
			(size 0.7112 0.6096)
			(layers "F.Cu" "F.Mask" "F.Paste")
			(net "R_PCA9546_I2C_SDA")
		)
		(zone
			(layer "F.Cu")
			(hatch none 0.5)
			(connect_pads
				(clearance 0)
			)
			(min_thickness 0.25)
			(keepout
				(tracks not_allowed)
				(vias allowed)
				(pads allowed)
				(copperpour not_allowed)
				(footprints allowed)
			)
			(placement
				(enabled no)
				(sheetname "")
			)
			(fill
				(thermal_gap 0.5)
				(thermal_bridge_width 0.5)
				(island_removal_mode 0)
			)
			(polygon
				(pts
					(xy 73.9902 -82.4738) (xy 74.1426 -82.4738) (xy 74.1426 -83.0834) (xy 73.9902 -83.0834)
				)
			)
		)
		(zone
			(layer "F.Cu")
			(hatch none 0.5)
			(connect_pads
				(clearance 0)
			)
			(min_thickness 0.25)
			(keepout
				(tracks allowed)
				(vias not_allowed)
				(pads allowed)
				(copperpour not_allowed)
				(footprints allowed)
			)
			(placement
				(enabled no)
				(sheetname "")
			)
			(fill
				(thermal_gap 0.5)
				(thermal_bridge_width 0.5)
				(island_removal_mode 0)
			)
			(polygon
				(pts
					(xy 73.9902 -82.4738) (xy 74.1426 -82.4738) (xy 74.1426 -83.0834) (xy 73.9902 -83.0834)
				)
			)
		)
	)
)
